(kicad_pcb
	(version 20260206)
	(generator "pcbnew")
	(generator_version "10.0")
	(general
		(thickness 1.6)
		(legacy_teardrops no)
	)
	(paper "A4")
	(title_block
		(title "timecard-production-celestica-r4006 — R4006-B0001-02_R01.brd")
		(comment 1 "Time Appliance Project (Time Card) / footprints 250-253 of 1113")
	)
	(layers
		(0 "F.Cu" signal "TOP")
		(4 "In1.Cu" signal "L02_GND1")
		(6 "In2.Cu" signal "L03_SIG1")
		(8 "In3.Cu" signal "L04_GND2")
		(10 "In4.Cu" signal "L05_VCC1")
		(12 "In5.Cu" signal "L06_VCC2")
		(14 "In6.Cu" signal "L07_GND3")
		(16 "In7.Cu" signal "L08_SIG2")
		(18 "In8.Cu" signal "L09_GND4")
		(2 "B.Cu" signal "BOTTOM")
		(9 "F.Adhes" user "F.Adhesive")
		(11 "B.Adhes" user "B.Adhesive")
		(13 "F.Paste" user "Package Geometry/Pastemask Top")
		(15 "B.Paste" user "Package Geometry/Pastemask Bottom")
		(5 "F.SilkS" user "Ref Des/Silkscreen Top")
		(7 "B.SilkS" user "Ref Des/Silkscreen Bottom")
		(1 "F.Mask" user "Board Geometry/Soldermask Top")
		(3 "B.Mask" user "Board Geometry/Soldermask Bottom")
		(17 "Dwgs.User" user "User.Drawings")
		(19 "Cmts.User" user "User.Comments")
		(21 "Eco1.User" user "User.Eco1")
		(23 "Eco2.User" user "User.Eco2")
		(25 "Edge.Cuts" user "Board Geometry/Outline")
		(27 "Margin" user)
		(31 "F.CrtYd" user "Package Geometry/Place Bound Top")
		(29 "B.CrtYd" user "Package Geometry/Place Bound Bottom")
		(35 "F.Fab" user "Ref Des/Assembly Top")
		(33 "B.Fab" user "Ref Des/Assembly Bottom")
	)
	(footprint ""
		(layer "F.Cu")
		(at 133.858 -22.098 180)
		(property "Reference" "R484"
			(at 0.127 5.04063 0)
			(unlocked yes)
			(layer "F.SilkS")
			(effects
				(font
					(size 0.7874 0.5842)
					(thickness 0.1524)
				)
			)
		)
		(property "Value" "VAL*"
			(at 0.02032 2.13233 180)
			(unlocked yes)
			(layer "F.Fab")
			(hide yes)
			(effects
				(font
					(size 0.7874 0.5842)
					(thickness 0.1524)
				)
			)
		)
		(property "Tolerance" "TOL*"
			(at 0.044704 3.05435 180)
			(unlocked yes)
			(layer "Cmts.User")
			(hide yes)
			(effects
				(font
					(size 0.7874 0.5842)
					(thickness 0.1524)
				)
			)
		)
		(property "User Part Number" "PARTNUM*"
			(at 0.02032 4.024884 180)
			(unlocked yes)
			(layer "Cmts.User")
			(hide yes)
			(effects
				(font
					(size 0.7874 0.5842)
					(thickness 0.1524)
				)
			)
		)
		(property "Device Type" "RESISTOR-G155-11001-01,1KOHM,1%"
			(at 0.008382 1.210564 180)
			(unlocked yes)
			(layer "F.Fab")
			(hide yes)
			(effects
				(font
					(size 0.7874 0.5842)
					(thickness 0.1524)
				)
			)
		)
		(duplicate_pad_numbers_are_jumpers no)
		(fp_line
			(start 1.143 0.5588)
			(end 1.143 -0.5588)
			(stroke
				(width 0.1)
				(type default)
			)
			(layer "F.SilkS")
		)
		(fp_line
			(start 1.143 -0.5588)
			(end -1.143 -0.5588)
			(stroke
				(width 0.1)
				(type default)
			)
			(layer "F.SilkS")
		)
		(fp_line
			(start -1.143 0.5588)
			(end 1.143 0.5588)
			(stroke
				(width 0.1)
				(type default)
			)
			(layer "F.SilkS")
		)
		(fp_line
			(start -1.143 -0.5588)
			(end -1.143 0.5588)
			(stroke
				(width 0.1)
				(type default)
			)
			(layer "F.SilkS")
		)
		(fp_poly
			(pts
				(xy -1.143 0.5588) (xy 1.143 0.5588) (xy 1.143 -0.5588) (xy -1.143 -0.5588)
			)
			(stroke
				(width 0)
				(type default)
			)
			(fill no)
			(layer "F.CrtYd")
		)
		(fp_line
			(start 0.508 0.3048)
			(end 0.508 -0.3048)
			(stroke
				(width 0.1)
				(type default)
			)
			(layer "F.Fab")
		)
		(fp_line
			(start 0.508 -0.3048)
			(end -0.508 -0.3048)
			(stroke
				(width 0.1)
				(type default)
			)
			(layer "F.Fab")
		)
		(fp_line
			(start -0.508 0.3048)
			(end 0.508 0.3048)
			(stroke
				(width 0.1)
				(type default)
			)
			(layer "F.Fab")
		)
		(fp_line
			(start -0.508 -0.3048)
			(end -0.508 0.3048)
			(stroke
				(width 0.1)
				(type default)
			)
			(layer "F.Fab")
		)
		(pad "1" smd rect
			(at -0.5334 0 180)
			(size 0.7112 0.6096)
			(layers "F.Cu" "F.Mask" "F.Paste")
			(net "SG")
		)
		(pad "2" smd rect
			(at 0.5334 0 180)
			(size 0.7112 0.6096)
			(layers "F.Cu" "F.Mask" "F.Paste")
			(net "UNNAMED_524_RESISTOR_I463_2")
		)
		(zone
			(layer "F.Cu")
			(hatch none 0.5)
			(connect_pads
				(clearance 0)
			)
			(min_thickness 0.25)
			(keepout
				(tracks allowed)
				(vias not_allowed)
				(pads allowed)
				(copperpour not_allowed)
				(footprints allowed)
			)
			(placement
				(enabled no)
				(sheetname "")
			)
			(fill
				(thermal_gap 0.5)
				(thermal_bridge_width 0.5)
				(island_removal_mode 0)
			)
			(polygon
				(pts
					(xy 133.9342 -22.4028) (xy 133.7818 -22.4028) (xy 133.7818 -21.7932) (xy 133.9342 -21.7932)
				)
			)
		)
		(zone
			(layer "F.Cu")
			(hatch none 0.5)
			(connect_pads
				(clearance 0)
			)
			(min_thickness 0.25)
			(keepout
				(tracks not_allowed)
				(vias allowed)
				(pads allowed)
				(copperpour not_allowed)
				(footprints allowed)
			)
			(placement
				(enabled no)
				(sheetname "")
			)
			(fill
				(thermal_gap 0.5)
				(thermal_bridge_width 0.5)
				(island_removal_mode 0)
			)
			(polygon
				(pts
					(xy 133.9342 -22.4028) (xy 133.7818 -22.4028) (xy 133.7818 -21.7932) (xy 133.9342 -21.7932)
				)
			)
		)
	)
	(footprint ""
		(layer "F.Cu")
		(at 146.304 -53.848 -90)
		(property "Reference" "C257"
			(at 1.27 -2.70637 90)
			(unlocked yes)
			(layer "F.SilkS")
			(effects
				(font
					(size 0.7874 0.5842)
					(thickness 0.1524)
				)
			)
		)
		(property "Value" "VAL*"
			(at 0.0762 3.134106 270)
			(unlocked yes)
			(layer "F.Fab")
			(hide yes)
			(effects
				(font
					(size 0.7874 0.5842)
					(thickness 0.1524)
				)
			)
		)
		(property "Device Type" "CAPACITOR-G107-0F106-EM,10UF,2A"
			(at 0.0508 2.194306 270)
			(unlocked yes)
			(layer "F.Fab")
			(hide yes)
			(effects
				(font
					(size 0.7874 0.5842)
					(thickness 0.1524)
				)
			)
		)
		(property "User Part Number" "PARTNUM*"
			(at 0.1016 5.013706 270)
			(unlocked yes)
			(layer "Cmts.User")
			(hide yes)
			(effects
				(font
					(size 0.7874 0.5842)
					(thickness 0.1524)
				)
			)
		)
		(property "Tolerance" "TOL*"
			(at 0.0762 4.048506 270)
			(unlocked yes)
			(layer "Cmts.User")
			(hide yes)
			(effects
				(font
					(size 0.7874 0.5842)
					(thickness 0.1524)
				)
			)
		)
		(duplicate_pad_numbers_are_jumpers no)
		(fp_line
			(start -1.5748 0.9398)
			(end 1.5748 0.9398)
			(stroke
				(width 0.1)
				(type default)
			)
			(layer "F.SilkS")
		)
		(fp_line
			(start 1.5748 0.9398)
			(end 1.5748 -0.9398)
			(stroke
				(width 0.1)
				(type default)
			)
			(layer "F.SilkS")
		)
		(fp_line
			(start -1.5748 -0.9398)
			(end -1.5748 0.9398)
			(stroke
				(width 0.1)
				(type default)
			)
			(layer "F.SilkS")
		)
		(fp_line
			(start 1.5748 -0.9398)
			(end -1.5748 -0.9398)
			(stroke
				(width 0.1)
				(type default)
			)
			(layer "F.SilkS")
		)
		(fp_rect
			(start 1.5748 0.9398)
			(end -1.5748 -0.9398)
			(stroke
				(width 0)
				(type default)
			)
			(fill no)
			(layer "F.CrtYd")
		)
		(fp_line
			(start -1.016 0.635)
			(end 1.016 0.635)
			(stroke
				(width 0.1)
				(type default)
			)
			(layer "F.Fab")
		)
		(fp_line
			(start 1.016 0.635)
			(end 1.016 -0.635)
			(stroke
				(width 0.1)
				(type default)
			)
			(layer "F.Fab")
		)
		(fp_line
			(start -1.016 -0.635)
			(end -1.016 0.635)
			(stroke
				(width 0.1)
				(type default)
			)
			(layer "F.Fab")
		)
		(fp_line
			(start 1.016 -0.635)
			(end -1.016 -0.635)
			(stroke
				(width 0.1)
				(type default)
			)
			(layer "F.Fab")
		)
		(pad "1" smd rect
			(at -0.8382 0 270)
			(size 0.9652 1.3716)
			(layers "F.Cu" "F.Mask" "F.Paste")
			(net "VIN_XP1R0V")
		)
		(pad "2" smd rect
			(at 0.8382 0 270)
			(size 0.9652 1.3716)
			(layers "F.Cu" "F.Mask" "F.Paste")
			(net "SG")
		)
		(zone
			(layer "F.Cu")
			(hatch none 0.5)
			(connect_pads
				(clearance 0)
			)
			(min_thickness 0.25)
			(keepout
				(tracks allowed)
				(vias not_allowed)
				(pads allowed)
				(copperpour not_allowed)
				(footprints allowed)
			)
			(placement
				(enabled no)
				(sheetname "")
			)
			(fill
				(thermal_gap 0.5)
				(thermal_bridge_width 0.5)
				(island_removal_mode 0)
			)
			(polygon
				(pts
					(xy 145.669 -53.6194) (xy 146.939 -53.6194) (xy 146.939 -54.0766) (xy 145.669 -54.0766)
				)
			)
		)
	)
	(footprint ""
		(layer "F.Cu")
		(at 100.3808 -70.4596)
		(property "Reference" "C192"
			(at 2.7432 0.14097 0)
			(unlocked yes)
			(layer "F.SilkS")
			(effects
				(font
					(size 0.7874 0.5842)
					(thickness 0.1524)
				)
			)
		)
		(property "Value" "VAL*"
			(at 0.193548 2.13614 0)
			(unlocked yes)
			(layer "F.Fab")
			(hide yes)
			(effects
				(font
					(size 0.7874 0.5842)
					(thickness 0.1524)
				)
			)
		)
		(property "User Part Number" "PARTNUM*"
			(at 0.216154 4.185666 0)
			(unlocked yes)
			(layer "Cmts.User")
			(hide yes)
			(effects
				(font
					(size 0.7874 0.5842)
					(thickness 0.1524)
				)
			)
		)
		(property "Device Type" "CAPACITOR-G104-0B103-EK,0.01UFA"
			(at 0.184404 1.180592 0)
			(unlocked yes)
			(layer "F.Fab")
			(hide yes)
			(effects
				(font
					(size 0.7874 0.5842)
					(thickness 0.1524)
				)
			)
		)
		(property "Tolerance" "TOL*"
			(at 0.216154 3.1496 0)
			(unlocked yes)
			(layer "Cmts.User")
			(hide yes)
			(effects
				(font
					(size 0.7874 0.5842)
					(thickness 0.1524)
				)
			)
		)
		(duplicate_pad_numbers_are_jumpers no)
		(fp_line
			(start -0.671322 -0.4445)
			(end 0.671322 -0.4445)
			(stroke
				(width 0.1)
				(type default)
			)
			(layer "F.SilkS")
		)
		(fp_line
			(start -0.671322 0.4445)
			(end -0.671322 -0.4445)
			(stroke
				(width 0.1)
				(type default)
			)
			(layer "F.SilkS")
		)
		(fp_line
			(start 0.671322 -0.4445)
			(end 0.671322 0.4445)
			(stroke
				(width 0.1)
				(type default)
			)
			(layer "F.SilkS")
		)
		(fp_line
			(start 0.671322 0.4445)
			(end -0.671322 0.4445)
			(stroke
				(width 0.1)
				(type default)
			)
			(layer "F.SilkS")
		)
		(fp_rect
			(start -0.671322 -0.4445)
			(end 0.671322 0.4445)
			(stroke
				(width 0)
				(type default)
			)
			(fill no)
			(layer "F.CrtYd")
		)
		(fp_line
			(start -0.31496 -0.1651)
			(end -0.31496 0.1651)
			(stroke
				(width 0.1)
				(type default)
			)
			(layer "F.Fab")
		)
		(fp_line
			(start -0.31496 0.1651)
			(end 0.31496 0.1651)
			(stroke
				(width 0.1)
				(type default)
			)
			(layer "F.Fab")
		)
		(fp_line
			(start 0.31496 -0.1651)
			(end -0.31496 -0.1651)
			(stroke
				(width 0.1)
				(type default)
			)
			(layer "F.Fab")
		)
		(fp_line
			(start 0.31496 0.1651)
			(end 0.31496 -0.1651)
			(stroke
				(width 0.1)
				(type default)
			)
			(layer "F.Fab")
		)
		(pad "1" smd rect
			(at -0.264922 0)
			(size 0.3048 0.381)
			(layers "F.Cu" "F.Mask" "F.Paste")
			(net "XP1R2V_PG_R")
		)
		(pad "2" smd rect
			(at 0.264922 0)
			(size 0.3048 0.381)
			(layers "F.Cu" "F.Mask" "F.Paste")
			(net "SG")
		)
		(zone
			(layer "F.Cu")
			(hatch none 0.5)
			(connect_pads
				(clearance 0)
			)
			(min_thickness 0.25)
			(keepout
				(tracks allowed)
				(vias not_allowed)
				(pads allowed)
				(copperpour not_allowed)
				(footprints allowed)
			)
			(placement
				(enabled no)
				(sheetname "")
			)
			(fill
				(thermal_gap 0.5)
				(thermal_bridge_width 0.5)
				(island_removal_mode 0)
			)
			(polygon
				(pts
					(xy 100.268278 -70.6501) (xy 100.268278 -70.2691) (xy 100.493322 -70.2691) (xy 100.493322 -70.6501)
				)
			)
		)
	)
	(footprint ""
		(layer "F.Cu")
		(at 4.073906 -47.099982)
		(property "Reference" "J4"
			(at 4.816094 -2.390648 0)
			(unlocked yes)
			(layer "F.SilkS")
			(effects
				(font
					(size 0.7874 0.5842)
					(thickness 0.1524)
				)
			)
		)
		(property "Value" ""
			(at 0 0 0)
			(layer "F.Fab")
			(effects
				(font
					(size 1.27 1.27)
				)
			)
		)
		(property "Device Type" "CONN_JACK_1P_GH4_S_TH-G200-130A"
			(at -5.098288 5.899912 0)
			(unlocked yes)
			(layer "F.Fab")
			(hide yes)
			(effects
				(font
					(size 0.7874 0.5842)
					(thickness 0.1524)
				)
			)
		)
		(property "User Part Number" "PARTNUM*"
			(at -5.098288 7.093712 0)
			(unlocked yes)
			(layer "Cmts.User")
			(hide yes)
			(effects
				(font
					(size 0.7874 0.5842)
					(thickness 0.1524)
				)
			)
		)
		(duplicate_pad_numbers_are_jumpers no)
		(fp_line
			(start -13.953998 -3.937)
			(end 3.937 -3.937)
			(stroke
				(width 0.1)
				(type default)
			)
			(layer "F.SilkS")
		)
		(fp_line
			(start -13.953998 3.937)
			(end -13.953998 -3.937)
			(stroke
				(width 0.1)
				(type default)
			)
			(layer "F.SilkS")
		)
		(fp_line
			(start 3.937 -3.937)
			(end 3.937 3.937)
			(stroke
				(width 0.1)
				(type default)
			)
			(layer "F.SilkS")
		)
		(fp_line
			(start 3.937 3.937)
			(end -13.953998 3.937)
			(stroke
				(width 0.1)
				(type default)
			)
			(layer "F.SilkS")
		)
		(fp_rect
			(start -8.763 8.763)
			(end 8.763 -8.763)
			(stroke
				(width 0)
				(type default)
			)
			(fill no)
			(layer "B.CrtYd")
		)
		(fp_rect
			(start -14.207998 4.191)
			(end 4.191 -4.191)
			(stroke
				(width 0)
				(type default)
			)
			(fill no)
			(layer "F.CrtYd")
		)
		(fp_line
			(start -13.699998 -3.599942)
			(end 3.599942 -3.599942)
			(stroke
				(width 0.1)
				(type default)
			)
			(layer "F.Fab")
		)
		(fp_line
			(start -13.699998 3.599942)
			(end -13.699998 -3.599942)
			(stroke
				(width 0.1)
				(type default)
			)
			(layer "F.Fab")
		)
		(fp_line
			(start 3.599942 -3.599942)
			(end 3.599942 3.599942)
			(stroke
				(width 0.1)
				(type default)
			)
			(layer "F.Fab")
		)
		(fp_line
			(start 3.599942 3.599942)
			(end -13.699998 3.599942)
			(stroke
				(width 0.1)
				(type default)
			)
			(layer "F.Fab")
		)
		(fp_text user "GH3"
			(at -1.660906 4.332732 0)
			(unlocked yes)
			(layer "F.SilkS")
			(effects
				(font
					(size 0.635 0.4064)
					(thickness 0.1524)
				)
			)
		)
		(fp_text user "GH1"
			(at -0.263906 -4.227068 0)
			(unlocked yes)
			(layer "F.SilkS")
			(effects
				(font
					(size 0.635 0.4064)
					(thickness 0.1524)
				)
			)
		)
		(fp_text user "GH2"
			(at 2.911094 -4.354068 0)
			(unlocked yes)
			(layer "F.SilkS")
			(effects
				(font
					(size 0.635 0.4064)
					(thickness 0.1524)
				)
			)
		)
		(fp_text user "1"
			(at 4.015994 -0.104648 0)
			(unlocked yes)
			(layer "F.SilkS")
			(effects
				(font
					(size 0.7874 0.5842)
					(thickness 0.1524)
				)
				(justify left)
			)
		)
		(fp_text user "GH4"
			(at 4.466844 3.284982 90)
			(unlocked yes)
			(layer "F.SilkS")
			(effects
				(font
					(size 0.635 0.4064)
					(thickness 0.1524)
				)
			)
		)
		(fp_text user "GH1"
			(at -2.549906 -4.295648 0)
			(unlocked yes)
			(layer "F.Fab")
			(effects
				(font
					(size 0.7874 0.5842)
					(thickness 0.1524)
				)
			)
		)
		(fp_text user "GH3"
			(at -2.549906 4.215638 0)
			(unlocked yes)
			(layer "F.Fab")
			(effects
				(font
					(size 0.7874 0.5842)
					(thickness 0.1524)
				)
			)
		)
		(fp_text user "GH2"
			(at 2.149094 -4.168648 0)
			(unlocked yes)
			(layer "F.Fab")
			(effects
				(font
					(size 0.7874 0.5842)
					(thickness 0.1524)
				)
			)
		)
		(fp_text user "GH4"
			(at 2.54 4.64947 0)
			(unlocked yes)
			(layer "F.Fab")
			(effects
				(font
					(size 0.7874 0.5842)
					(thickness 0.1524)
				)
			)
		)
		(fp_text user "1"
			(at 3.800094 -0.356362 0)
			(unlocked yes)
			(layer "F.Fab")
			(effects
				(font
					(size 0.7874 0.5842)
					(thickness 0.1524)
				)
				(justify left)
			)
		)
		(pad "1" thru_hole circle
			(at 0 0)
			(size 2.1844 2.1844)
			(drill 1.4986)
			(layers "*.Cu" "*.Mask")
			(remove_unused_layers no)
			(net "SMA2_SIG_IO_CONN")
			(padstack
				(mode front_inner_back)
				(layer "Inner"
					(shape circle)
					(size 2.1844 2.1844)
					(clearance -0.0508)
				)
				(layer "B.Cu"
					(shape circle)
					(size 2.1844 2.1844)
				)
			)
		)
		(pad "GH1" thru_hole circle
			(at -2.54 -2.54)
			(size 2.286 2.286)
			(drill 1.6002)
			(layers "*.Cu" "*.Mask")
			(remove_unused_layers no)
			(net "SG")
			(padstack
				(mode front_inner_back)
				(layer "Inner"
					(shape circle)
					(size 2.286 2.286)
					(clearance -0.0508)
				)
				(layer "B.Cu"
					(shape circle)
					(size 2.286 2.286)
				)
			)
		)
		(pad "GH2" thru_hole circle
			(at 2.54 -2.54)
			(size 2.286 2.286)
			(drill 1.6002)
			(layers "*.Cu" "*.Mask")
			(remove_unused_layers no)
			(net "SG")
			(padstack
				(mode front_inner_back)
				(layer "Inner"
					(shape circle)
					(size 2.286 2.286)
					(clearance -0.0508)
				)
				(layer "B.Cu"
					(shape circle)
					(size 2.286 2.286)
				)
			)
		)
		(pad "GH3" thru_hole circle
			(at -2.54 2.54)
			(size 2.286 2.286)
			(drill 1.6002)
			(layers "*.Cu" "*.Mask")
			(remove_unused_layers no)
			(net "SG")
			(padstack
				(mode front_inner_back)
				(layer "Inner"
					(shape circle)
					(size 2.286 2.286)
					(clearance -0.0508)
				)
				(layer "B.Cu"
					(shape circle)
					(size 2.286 2.286)
				)
			)
		)
		(pad "GH4" thru_hole circle
			(at 2.54 2.54)
			(size 2.286 2.286)
			(drill 1.6002)
			(layers "*.Cu" "*.Mask")
			(remove_unused_layers no)
			(net "SG")
			(padstack
				(mode front_inner_back)
				(layer "Inner"
					(shape circle)
					(size 2.286 2.286)
					(clearance -0.0508)
				)
				(layer "B.Cu"
					(shape circle)
					(size 2.286 2.286)
				)
			)
		)
	)
)
